(kicad_pcb
	(version 20260206)
	(generator "pcbnew")
	(generator_version "10.0")
	(general
		(thickness 1.6)
		(legacy_teardrops no)
	)
	(paper "A4")
	(title_block
		(title "04192023_DAF0TMB3IC0_F0TG_MB_C_brd_V02_OCP.brd")
		(comment 1 "Grand Teton / footprints 3888-3895 of 8354")
	)
	(layers
		(0 "F.Cu" signal "TOP")
		(4 "In1.Cu" signal "GND")
		(6 "In2.Cu" signal "IN1")
		(8 "In3.Cu" signal "GND1")
		(10 "In4.Cu" signal "IN2")
		(12 "In5.Cu" signal "GND2")
		(14 "In6.Cu" signal "IN3")
		(16 "In7.Cu" signal "GND3")
		(18 "In8.Cu" signal "VCC")
		(20 "In9.Cu" signal "VCC1")
		(22 "In10.Cu" signal "GND4")
		(24 "In11.Cu" signal "IN4")
		(26 "In12.Cu" signal "GND5")
		(28 "In13.Cu" signal "IN5")
		(30 "In14.Cu" signal "GND6")
		(32 "In15.Cu" signal "IN6")
		(34 "In16.Cu" signal "GND7")
		(2 "B.Cu" signal "BOTTOM")
		(9 "F.Adhes" user "F.Adhesive")
		(11 "B.Adhes" user "B.Adhesive")
		(13 "F.Paste" user "Package Geometry/Pastemask Top")
		(15 "B.Paste" user "Package Geometry/Pastemask Bottom")
		(5 "F.SilkS" user "Ref Des/Silkscreen Top")
		(7 "B.SilkS" user "Ref Des/Silkscreen Bottom")
		(1 "F.Mask" user "Board Geometry/Soldermask Top")
		(3 "B.Mask" user "Board Geometry/Soldermask Bottom")
		(17 "Dwgs.User" user "User.Drawings")
		(19 "Cmts.User" user "User.Comments")
		(21 "Eco1.User" user "User.Eco1")
		(23 "Eco2.User" user "User.Eco2")
		(25 "Edge.Cuts" user "Board Geometry/Outline")
		(27 "Margin" user)
		(31 "F.CrtYd" user "Package Geometry/Place Bound Top")
		(29 "B.CrtYd" user "Package Geometry/Place Bound Bottom")
		(35 "F.Fab" user "Ref Des/Assembly Top")
		(33 "B.Fab" user "Ref Des/Assembly Bottom")
	)
	(footprint ""
		(layer "F.Cu")
		(at 191.41694 -400.309842)
		(property "Reference" "R3934"
			(at 0 0 0)
			(layer "F.SilkS")
			(hide yes)
			(effects
				(font
					(size 1.27 1.27)
				)
			)
		)
		(property "Value" ""
			(at 0 0 0)
			(layer "F.Fab")
			(effects
				(font
					(size 1.27 1.27)
				)
			)
		)
		(duplicate_pad_numbers_are_jumpers no)
		(fp_line
			(start -0.7874 -0.4064)
			(end 0.7874 -0.4064)
			(stroke
				(width 0.1524)
				(type default)
			)
			(layer "F.SilkS")
		)
		(fp_line
			(start -0.7874 0.4064)
			(end -0.7874 -0.4064)
			(stroke
				(width 0.1524)
				(type default)
			)
			(layer "F.SilkS")
		)
		(fp_line
			(start 0.7874 -0.4064)
			(end 0.7874 0.4064)
			(stroke
				(width 0.1524)
				(type default)
			)
			(layer "F.SilkS")
		)
		(fp_line
			(start 0.7874 0.4064)
			(end -0.7874 0.4064)
			(stroke
				(width 0.1524)
				(type default)
			)
			(layer "F.SilkS")
		)
		(fp_line
			(start -0.67945 -0.305054)
			(end -0.12065 -0.305054)
			(stroke
				(width 0.1)
				(type default)
			)
			(layer "F.Fab")
		)
		(fp_line
			(start -0.67945 0.3048)
			(end -0.67945 -0.305054)
			(stroke
				(width 0.1)
				(type default)
			)
			(layer "F.Fab")
		)
		(fp_line
			(start -0.12065 -0.305054)
			(end -0.12065 -0.2794)
			(stroke
				(width 0.1)
				(type default)
			)
			(layer "F.Fab")
		)
		(fp_line
			(start -0.12065 -0.2794)
			(end 0.12065 -0.2794)
			(stroke
				(width 0.1)
				(type default)
			)
			(layer "F.Fab")
		)
		(fp_line
			(start -0.12065 0.2794)
			(end -0.12065 0.3048)
			(stroke
				(width 0.1)
				(type default)
			)
			(layer "F.Fab")
		)
		(fp_line
			(start -0.12065 0.3048)
			(end -0.67945 0.3048)
			(stroke
				(width 0.1)
				(type default)
			)
			(layer "F.Fab")
		)
		(fp_line
			(start 0.120396 0.2794)
			(end -0.12065 0.2794)
			(stroke
				(width 0.1)
				(type default)
			)
			(layer "F.Fab")
		)
		(fp_line
			(start 0.120396 0.3048)
			(end 0.120396 0.2794)
			(stroke
				(width 0.1)
				(type default)
			)
			(layer "F.Fab")
		)
		(fp_line
			(start 0.12065 -0.3048)
			(end 0.67945 -0.3048)
			(stroke
				(width 0.1)
				(type default)
			)
			(layer "F.Fab")
		)
		(fp_line
			(start 0.12065 -0.2794)
			(end 0.12065 -0.3048)
			(stroke
				(width 0.1)
				(type default)
			)
			(layer "F.Fab")
		)
		(fp_line
			(start 0.67945 -0.3048)
			(end 0.67945 0.3048)
			(stroke
				(width 0.1)
				(type default)
			)
			(layer "F.Fab")
		)
		(fp_line
			(start 0.67945 0.3048)
			(end 0.120396 0.3048)
			(stroke
				(width 0.1)
				(type default)
			)
			(layer "F.Fab")
		)
		(pad "1" smd circle
			(at -0.40005 0)
			(size 0 0)
			(layers "F.Cu" "F.Mask" "F.Paste")
			(net "HSC_D_OC_R")
		)
		(pad "2" smd circle
			(at 0.40005 0)
			(size 0 0)
			(layers "F.Cu" "F.Mask" "F.Paste")
			(net "HSC_D_OC")
		)
	)
	(footprint ""
		(layer "F.Cu")
		(at 173.2788 -385.5212 90)
		(property "Reference" "C366"
			(at 0 0 90)
			(layer "F.SilkS")
			(hide yes)
			(effects
				(font
					(size 1.27 1.27)
				)
			)
		)
		(property "Value" ""
			(at 0 0 90)
			(layer "F.Fab")
			(effects
				(font
					(size 1.27 1.27)
				)
			)
		)
		(duplicate_pad_numbers_are_jumpers no)
		(fp_line
			(start 1.524 -0.762)
			(end 1.524 0.762)
			(stroke
				(width 0.1524)
				(type default)
			)
			(layer "F.SilkS")
		)
		(fp_line
			(start -1.524 -0.762)
			(end 1.524 -0.762)
			(stroke
				(width 0.1524)
				(type default)
			)
			(layer "F.SilkS")
		)
		(fp_line
			(start 1.524 0.762)
			(end -1.524 0.762)
			(stroke
				(width 0.1524)
				(type default)
			)
			(layer "F.SilkS")
		)
		(fp_line
			(start -1.524 0.762)
			(end -1.524 -0.762)
			(stroke
				(width 0.1524)
				(type default)
			)
			(layer "F.SilkS")
		)
		(fp_line
			(start 1.1049 -0.724916)
			(end -1.1049 -0.724916)
			(stroke
				(width 0.1)
				(type default)
			)
			(layer "F.Fab")
		)
		(fp_line
			(start -1.1049 -0.724916)
			(end -1.1049 0.724916)
			(stroke
				(width 0.1)
				(type default)
			)
			(layer "F.Fab")
		)
		(fp_line
			(start 1.1049 0.724916)
			(end 1.1049 -0.724916)
			(stroke
				(width 0.1)
				(type default)
			)
			(layer "F.Fab")
		)
		(fp_line
			(start -1.1049 0.724916)
			(end 1.1049 0.724916)
			(stroke
				(width 0.1)
				(type default)
			)
			(layer "F.Fab")
		)
		(pad "1" smd rect
			(at -0.889 0 270)
			(size 1.016 1.27)
			(layers "F.Cu" "F.Mask" "F.Paste")
			(net "P1V8_CPU1_RT_1D")
		)
		(pad "2" smd rect
			(at 0.889 0 270)
			(size 1.016 1.27)
			(layers "F.Cu" "F.Mask" "F.Paste")
			(net "GND")
		)
	)
	(footprint ""
		(layer "F.Cu")
		(at 137.196068 -74.236072 180)
		(property "Reference" "PC6020"
			(at 0 0 180)
			(layer "F.SilkS")
			(hide yes)
			(effects
				(font
					(size 1.27 1.27)
				)
			)
		)
		(property "Value" ""
			(at 0 0 180)
			(layer "F.Fab")
			(effects
				(font
					(size 1.27 1.27)
				)
			)
		)
		(duplicate_pad_numbers_are_jumpers no)
		(fp_line
			(start 0.7874 0.4064)
			(end -0.7874 0.4064)
			(stroke
				(width 0.1524)
				(type default)
			)
			(layer "F.SilkS")
		)
		(fp_line
			(start 0.7874 -0.4064)
			(end 0.7874 0.4064)
			(stroke
				(width 0.1524)
				(type default)
			)
			(layer "F.SilkS")
		)
		(fp_line
			(start -0.7874 0.4064)
			(end -0.7874 -0.4064)
			(stroke
				(width 0.1524)
				(type default)
			)
			(layer "F.SilkS")
		)
		(fp_line
			(start -0.7874 -0.4064)
			(end 0.7874 -0.4064)
			(stroke
				(width 0.1524)
				(type default)
			)
			(layer "F.SilkS")
		)
		(fp_line
			(start 0.67945 0.3048)
			(end 0.120396 0.3048)
			(stroke
				(width 0.1)
				(type default)
			)
			(layer "F.Fab")
		)
		(fp_line
			(start 0.67945 -0.3048)
			(end 0.67945 0.3048)
			(stroke
				(width 0.1)
				(type default)
			)
			(layer "F.Fab")
		)
		(fp_line
			(start 0.12065 -0.2794)
			(end 0.12065 -0.3048)
			(stroke
				(width 0.1)
				(type default)
			)
			(layer "F.Fab")
		)
		(fp_line
			(start 0.12065 -0.3048)
			(end 0.67945 -0.3048)
			(stroke
				(width 0.1)
				(type default)
			)
			(layer "F.Fab")
		)
		(fp_line
			(start 0.120396 0.3048)
			(end 0.120396 0.2794)
			(stroke
				(width 0.1)
				(type default)
			)
			(layer "F.Fab")
		)
		(fp_line
			(start 0.120396 0.2794)
			(end -0.12065 0.2794)
			(stroke
				(width 0.1)
				(type default)
			)
			(layer "F.Fab")
		)
		(fp_line
			(start -0.12065 0.3048)
			(end -0.67945 0.3048)
			(stroke
				(width 0.1)
				(type default)
			)
			(layer "F.Fab")
		)
		(fp_line
			(start -0.12065 0.2794)
			(end -0.12065 0.3048)
			(stroke
				(width 0.1)
				(type default)
			)
			(layer "F.Fab")
		)
		(fp_line
			(start -0.12065 -0.2794)
			(end 0.12065 -0.2794)
			(stroke
				(width 0.1)
				(type default)
			)
			(layer "F.Fab")
		)
		(fp_line
			(start -0.12065 -0.305054)
			(end -0.12065 -0.2794)
			(stroke
				(width 0.1)
				(type default)
			)
			(layer "F.Fab")
		)
		(fp_line
			(start -0.67945 0.3048)
			(end -0.67945 -0.305054)
			(stroke
				(width 0.1)
				(type default)
			)
			(layer "F.Fab")
		)
		(fp_line
			(start -0.67945 -0.305054)
			(end -0.12065 -0.305054)
			(stroke
				(width 0.1)
				(type default)
			)
			(layer "F.Fab")
		)
		(pad "1" smd circle
			(at -0.40005 0 180)
			(size 0 0)
			(layers "F.Cu" "F.Mask" "F.Paste")
			(net "P12V_AUX")
		)
		(pad "2" smd circle
			(at 0.40005 0 180)
			(size 0 0)
			(layers "F.Cu" "F.Mask" "F.Paste")
			(net "GND")
		)
	)
	(footprint ""
		(layer "F.Cu")
		(at 295.30421 -404.422102 -90)
		(property "Reference" "C664"
			(at 0 0 270)
			(layer "F.SilkS")
			(hide yes)
			(effects
				(font
					(size 1.27 1.27)
				)
			)
		)
		(property "Value" ""
			(at 0 0 270)
			(layer "F.Fab")
			(effects
				(font
					(size 1.27 1.27)
				)
			)
		)
		(duplicate_pad_numbers_are_jumpers no)
		(fp_line
			(start -0.299974 0.150114)
			(end -0.299974 -0.150114)
			(stroke
				(width 0.1)
				(type default)
			)
			(layer "F.Fab")
		)
		(fp_line
			(start 0.299974 0.150114)
			(end -0.299974 0.150114)
			(stroke
				(width 0.1)
				(type default)
			)
			(layer "F.Fab")
		)
		(fp_line
			(start -0.299974 -0.150114)
			(end 0.299974 -0.150114)
			(stroke
				(width 0.1)
				(type default)
			)
			(layer "F.Fab")
		)
		(fp_line
			(start 0.299974 -0.150114)
			(end 0.299974 0.150114)
			(stroke
				(width 0.1)
				(type default)
			)
			(layer "F.Fab")
		)
		(pad "1" smd rect
			(at -0.2667 0 270)
			(size 0.3048 0.381)
			(layers "F.Cu" "F.Mask" "F.Paste")
			(net "P1V8_CPU0_RT_1D")
		)
		(pad "2" smd rect
			(at 0.2667 0 270)
			(size 0.3048 0.381)
			(layers "F.Cu" "F.Mask" "F.Paste")
			(net "GND")
		)
	)
	(footprint ""
		(layer "F.Cu")
		(at 453.043544 -25.638506 180)
		(property "Reference" "PR4524"
			(at 0 0 180)
			(layer "F.SilkS")
			(hide yes)
			(effects
				(font
					(size 1.27 1.27)
				)
			)
		)
		(property "Value" ""
			(at 0 0 180)
			(layer "F.Fab")
			(effects
				(font
					(size 1.27 1.27)
				)
			)
		)
		(duplicate_pad_numbers_are_jumpers no)
		(fp_line
			(start 0.7874 0.4064)
			(end -0.7874 0.4064)
			(stroke
				(width 0.1524)
				(type default)
			)
			(layer "F.SilkS")
		)
		(fp_line
			(start 0.7874 -0.4064)
			(end 0.7874 0.4064)
			(stroke
				(width 0.1524)
				(type default)
			)
			(layer "F.SilkS")
		)
		(fp_line
			(start -0.7874 0.4064)
			(end -0.7874 -0.4064)
			(stroke
				(width 0.1524)
				(type default)
			)
			(layer "F.SilkS")
		)
		(fp_line
			(start -0.7874 -0.4064)
			(end 0.7874 -0.4064)
			(stroke
				(width 0.1524)
				(type default)
			)
			(layer "F.SilkS")
		)
		(fp_line
			(start 0.67945 0.3048)
			(end 0.120396 0.3048)
			(stroke
				(width 0.1)
				(type default)
			)
			(layer "F.Fab")
		)
		(fp_line
			(start 0.67945 -0.3048)
			(end 0.67945 0.3048)
			(stroke
				(width 0.1)
				(type default)
			)
			(layer "F.Fab")
		)
		(fp_line
			(start 0.12065 -0.2794)
			(end 0.12065 -0.3048)
			(stroke
				(width 0.1)
				(type default)
			)
			(layer "F.Fab")
		)
		(fp_line
			(start 0.12065 -0.3048)
			(end 0.67945 -0.3048)
			(stroke
				(width 0.1)
				(type default)
			)
			(layer "F.Fab")
		)
		(fp_line
			(start 0.120396 0.3048)
			(end 0.120396 0.2794)
			(stroke
				(width 0.1)
				(type default)
			)
			(layer "F.Fab")
		)
		(fp_line
			(start 0.120396 0.2794)
			(end -0.12065 0.2794)
			(stroke
				(width 0.1)
				(type default)
			)
			(layer "F.Fab")
		)
		(fp_line
			(start -0.12065 0.3048)
			(end -0.67945 0.3048)
			(stroke
				(width 0.1)
				(type default)
			)
			(layer "F.Fab")
		)
		(fp_line
			(start -0.12065 0.2794)
			(end -0.12065 0.3048)
			(stroke
				(width 0.1)
				(type default)
			)
			(layer "F.Fab")
		)
		(fp_line
			(start -0.12065 -0.2794)
			(end 0.12065 -0.2794)
			(stroke
				(width 0.1)
				(type default)
			)
			(layer "F.Fab")
		)
		(fp_line
			(start -0.12065 -0.305054)
			(end -0.12065 -0.2794)
			(stroke
				(width 0.1)
				(type default)
			)
			(layer "F.Fab")
		)
		(fp_line
			(start -0.67945 0.3048)
			(end -0.67945 -0.305054)
			(stroke
				(width 0.1)
				(type default)
			)
			(layer "F.Fab")
		)
		(fp_line
			(start -0.67945 -0.305054)
			(end -0.12065 -0.305054)
			(stroke
				(width 0.1)
				(type default)
			)
			(layer "F.Fab")
		)
		(pad "1" smd circle
			(at -0.40005 0 180)
			(size 0 0)
			(layers "F.Cu" "F.Mask" "F.Paste")
			(net "P12V_OCP_SFF")
		)
		(pad "2" smd circle
			(at 0.40005 0 180)
			(size 0 0)
			(layers "F.Cu" "F.Mask" "F.Paste")
			(net "P12V_OCP_GATE_1")
		)
	)
	(footprint ""
		(layer "F.Cu")
		(at 338.693506 -335.12379 -90)
		(property "Reference" "PC87_1"
			(at 0 0 270)
			(layer "F.SilkS")
			(hide yes)
			(effects
				(font
					(size 1.27 1.27)
				)
			)
		)
		(property "Value" ""
			(at 0 0 270)
			(layer "F.Fab")
			(effects
				(font
					(size 1.27 1.27)
				)
			)
		)
		(duplicate_pad_numbers_are_jumpers no)
		(fp_line
			(start -0.7874 0.4064)
			(end -0.7874 -0.4064)
			(stroke
				(width 0.1524)
				(type default)
			)
			(layer "F.SilkS")
		)
		(fp_line
			(start 0.7874 0.4064)
			(end -0.7874 0.4064)
			(stroke
				(width 0.1524)
				(type default)
			)
			(layer "F.SilkS")
		)
		(fp_line
			(start -0.7874 -0.4064)
			(end 0.7874 -0.4064)
			(stroke
				(width 0.1524)
				(type default)
			)
			(layer "F.SilkS")
		)
		(fp_line
			(start 0.7874 -0.4064)
			(end 0.7874 0.4064)
			(stroke
				(width 0.1524)
				(type default)
			)
			(layer "F.SilkS")
		)
		(fp_line
			(start -0.67945 0.3048)
			(end -0.67945 -0.305054)
			(stroke
				(width 0.1)
				(type default)
			)
			(layer "F.Fab")
		)
		(fp_line
			(start -0.12065 0.3048)
			(end -0.67945 0.3048)
			(stroke
				(width 0.1)
				(type default)
			)
			(layer "F.Fab")
		)
		(fp_line
			(start 0.120396 0.3048)
			(end 0.120396 0.2794)
			(stroke
				(width 0.1)
				(type default)
			)
			(layer "F.Fab")
		)
		(fp_line
			(start 0.67945 0.3048)
			(end 0.120396 0.3048)
			(stroke
				(width 0.1)
				(type default)
			)
			(layer "F.Fab")
		)
		(fp_line
			(start -0.12065 0.2794)
			(end -0.12065 0.3048)
			(stroke
				(width 0.1)
				(type default)
			)
			(layer "F.Fab")
		)
		(fp_line
			(start 0.120396 0.2794)
			(end -0.12065 0.2794)
			(stroke
				(width 0.1)
				(type default)
			)
			(layer "F.Fab")
		)
		(fp_line
			(start -0.12065 -0.2794)
			(end 0.12065 -0.2794)
			(stroke
				(width 0.1)
				(type default)
			)
			(layer "F.Fab")
		)
		(fp_line
			(start 0.12065 -0.2794)
			(end 0.12065 -0.3048)
			(stroke
				(width 0.1)
				(type default)
			)
			(layer "F.Fab")
		)
		(fp_line
			(start 0.12065 -0.3048)
			(end 0.67945 -0.3048)
			(stroke
				(width 0.1)
				(type default)
			)
			(layer "F.Fab")
		)
		(fp_line
			(start 0.67945 -0.3048)
			(end 0.67945 0.3048)
			(stroke
				(width 0.1)
				(type default)
			)
			(layer "F.Fab")
		)
		(fp_line
			(start -0.67945 -0.305054)
			(end -0.12065 -0.305054)
			(stroke
				(width 0.1)
				(type default)
			)
			(layer "F.Fab")
		)
		(fp_line
			(start -0.12065 -0.305054)
			(end -0.12065 -0.2794)
			(stroke
				(width 0.1)
				(type default)
			)
			(layer "F.Fab")
		)
		(pad "1" smd circle
			(at -0.40005 0 270)
			(size 0 0)
			(layers "F.Cu" "F.Mask" "F.Paste")
			(net "SW_P12V_AUX_PVDDCR_CPU1_P0_FLT")
		)
		(pad "2" smd circle
			(at 0.40005 0 270)
			(size 0 0)
			(layers "F.Cu" "F.Mask" "F.Paste")
			(net "GND")
		)
	)
	(footprint ""
		(layer "F.Cu")
		(at 335.315306 -416.899344 -90)
		(property "Reference" "C6521"
			(at 0 0 270)
			(layer "F.SilkS")
			(hide yes)
			(effects
				(font
					(size 1.27 1.27)
				)
			)
		)
		(property "Value" ""
			(at 0 0 270)
			(layer "F.Fab")
			(effects
				(font
					(size 1.27 1.27)
				)
			)
		)
		(duplicate_pad_numbers_are_jumpers no)
		(fp_line
			(start -0.299974 0.150114)
			(end -0.299974 -0.150114)
			(stroke
				(width 0.1)
				(type default)
			)
			(layer "F.Fab")
		)
		(fp_line
			(start 0.299974 0.150114)
			(end -0.299974 0.150114)
			(stroke
				(width 0.1)
				(type default)
			)
			(layer "F.Fab")
		)
		(fp_line
			(start -0.299974 -0.150114)
			(end 0.299974 -0.150114)
			(stroke
				(width 0.1)
				(type default)
			)
			(layer "F.Fab")
		)
		(fp_line
			(start 0.299974 -0.150114)
			(end 0.299974 0.150114)
			(stroke
				(width 0.1)
				(type default)
			)
			(layer "F.Fab")
		)
		(pad "1" smd rect
			(at -0.2667 0 270)
			(size 0.3048 0.381)
			(layers "F.Cu" "F.Mask" "F.Paste")
			(net "P5E_CPU0_P0_TX_BUF_C_DP<10>")
		)
		(pad "2" smd rect
			(at 0.2667 0 270)
			(size 0.3048 0.381)
			(layers "F.Cu" "F.Mask" "F.Paste")
			(net "P5E_CPU0_P0_TX_BUF_DP<10>")
		)
	)
	(footprint ""
		(layer "F.Cu")
		(at 426.687488 -332.63586 -90)
		(property "Reference" "PC230"
			(at -4.97078 -12.749276 90)
			(unlocked yes)
			(layer "F.SilkS")
			(effects
				(font
					(size 0.7874 0.5842)
					(thickness 0.1524)
				)
				(justify left)
			)
		)
		(property "Value" ""
			(at 0 0 270)
			(layer "F.Fab")
			(effects
				(font
					(size 1.27 1.27)
				)
			)
		)
		(duplicate_pad_numbers_are_jumpers no)
		(fp_line
			(start -1.988058 2.750058)
			(end 2.750058 2.750058)
			(stroke
				(width 0.1524)
				(type default)
			)
			(layer "F.SilkS")
		)
		(fp_line
			(start 2.750058 2.750058)
			(end 2.750058 0.9398)
			(stroke
				(width 0.1524)
				(type default)
			)
			(layer "F.SilkS")
		)
		(fp_line
			(start -2.750058 1.988058)
			(end -1.988058 2.750058)
			(stroke
				(width 0.1524)
				(type default)
			)
			(layer "F.SilkS")
		)
		(fp_line
			(start -2.750058 0.9398)
			(end -2.750058 1.988058)
			(stroke
				(width 0.1524)
				(type default)
			)
			(layer "F.SilkS")
		)
		(fp_line
			(start 2.750058 -0.9398)
			(end 2.750058 -2.750058)
			(stroke
				(width 0.1524)
				(type default)
			)
			(layer "F.SilkS")
		)
		(fp_line
			(start -2.750058 -1.988058)
			(end -2.750058 -0.9398)
			(stroke
				(width 0.1524)
				(type default)
			)
			(layer "F.SilkS")
		)
		(fp_line
			(start -1.988058 -2.750058)
			(end -2.750058 -1.988058)
			(stroke
				(width 0.1524)
				(type default)
			)
			(layer "F.SilkS")
		)
		(fp_line
			(start 2.750058 -2.750058)
			(end -1.988058 -2.750058)
			(stroke
				(width 0.1524)
				(type default)
			)
			(layer "F.SilkS")
		)
		(fp_line
			(start -2.750058 2.750058)
			(end 2.750058 2.750058)
			(stroke
				(width 0.1)
				(type default)
			)
			(layer "F.Fab")
		)
		(fp_line
			(start 2.750058 2.750058)
			(end 2.750058 -2.750058)
			(stroke
				(width 0.1)
				(type default)
			)
			(layer "F.Fab")
		)
		(fp_line
			(start -2.750058 -2.750058)
			(end -2.750058 2.750058)
			(stroke
				(width 0.1)
				(type default)
			)
			(layer "F.Fab")
		)
		(fp_line
			(start 2.750058 -2.750058)
			(end -2.750058 -2.750058)
			(stroke
				(width 0.1)
				(type default)
			)
			(layer "F.Fab")
		)
		(pad "1" smd rect
			(at -2.199894 0)
			(size 1.6002 3.0226)
			(layers "F.Cu" "F.Mask" "F.Paste")
			(net "PVDD11_S3_P0")
		)
		(pad "2" smd rect
			(at 2.199894 0)
			(size 1.6002 3.0226)
			(layers "F.Cu" "F.Mask" "F.Paste")
			(net "GND")
		)
	)
)
